# SCM (Grand Teton) — schematic netlist excerpt (pin names and nets, part order shuffled) for the footprints in the layout excerpt that follows; sources: Cadence DE-HDL packaged netlist, KiCad conversion of 12092022_DA0F0TMDCD0_F0T_Management_Board_D_brd_V3_OCP.brd

R213  Q_RES  0 5% CHIP  pkg 0402LF  page 15 : A = P3V3_AUX ; B = P3V3_P1V8_SD2VDD
R666  Q_RES  0 5% CHIP  pkg 0402LF  page 29 : A = USB3_01_MUX_FB_TXN ; B = USB3_01_FB_TXN

(kicad_pcb
	(version 20260206)
	(generator "pcbnew")
	(generator_version "10.0")
	(general
		(thickness 1.6)
		(legacy_teardrops no)
	)
	(paper "A4")
	(title_block
		(title "12092022_DA0F0TMDCD0_F0T_Management_Board_D_brd_V3_OCP.brd")
		(comment 1 "Grand Teton / footprints 592-593 of 1440")
	)
	(layers
		(0 "F.Cu" signal "TOP")
		(4 "In1.Cu" signal "GND")
		(6 "In2.Cu" signal "IN1")
		(8 "In3.Cu" signal "GND1")
		(10 "In4.Cu" signal "IN2")
		(12 "In5.Cu" signal "VCC")
		(14 "In6.Cu" signal "VCC1")
		(16 "In7.Cu" signal "IN3")
		(18 "In8.Cu" signal "GND2")
		(20 "In9.Cu" signal "IN4")
		(22 "In10.Cu" signal "GND3")
		(2 "B.Cu" signal "BOTTOM")
		(9 "F.Adhes" user "F.Adhesive")
		(11 "B.Adhes" user "B.Adhesive")
		(13 "F.Paste" user "Package Geometry/Pastemask Top")
		(15 "B.Paste" user "Package Geometry/Pastemask Bottom")
		(5 "F.SilkS" user "Ref Des/Silkscreen Top")
		(7 "B.SilkS" user "Ref Des/Silkscreen Bottom")
		(1 "F.Mask" user "Board Geometry/Soldermask Top")
		(3 "B.Mask" user "Board Geometry/Soldermask Bottom")
		(17 "Dwgs.User" user "User.Drawings")
		(19 "Cmts.User" user "User.Comments")
		(21 "Eco1.User" user "User.Eco1")
		(23 "Eco2.User" user "User.Eco2")
		(25 "Edge.Cuts" user "Board Geometry/Outline")
		(27 "Margin" user)
		(31 "F.CrtYd" user "Package Geometry/Place Bound Top")
		(29 "B.CrtYd" user "Package Geometry/Place Bound Bottom")
		(35 "F.Fab" user "Ref Des/Assembly Top")
		(33 "B.Fab" user "Ref Des/Assembly Bottom")
	)
	(footprint ""
		(layer "F.Cu")
		(at 41.572942 -22.15642 -90)
		(property "Reference" "R666"
			(at 0 0 270)
			(layer "F.SilkS")
			(hide yes)
			(effects
				(font
					(size 1.27 1.27)
				)
			)
		)
		(property "Value" ""
			(at 0 0 270)
			(layer "F.Fab")
			(effects
				(font
					(size 1.27 1.27)
				)
			)
		)
		(duplicate_pad_numbers_are_jumpers no)
		(fp_line
			(start 0.7874 0.4064)
			(end -0.7874 0.4064)
			(stroke
				(width 0.1524)
				(type default)
			)
			(layer "F.SilkS")
		)
		(fp_line
			(start -0.7874 -0.4064)
			(end 0.7874 -0.4064)
			(stroke
				(width 0.1524)
				(type default)
			)
			(layer "F.SilkS")
		)
		(fp_line
			(start -0.67945 0.3048)
			(end -0.67945 -0.305054)
			(stroke
				(width 0.1)
				(type default)
			)
			(layer "F.Fab")
		)
		(fp_line
			(start -0.12065 0.3048)
			(end -0.67945 0.3048)
			(stroke
				(width 0.1)
				(type default)
			)
			(layer "F.Fab")
		)
		(fp_line
			(start 0.120396 0.3048)
			(end 0.120396 0.2794)
			(stroke
				(width 0.1)
				(type default)
			)
			(layer "F.Fab")
		)
		(fp_line
			(start 0.67945 0.3048)
			(end 0.120396 0.3048)
			(stroke
				(width 0.1)
				(type default)
			)
			(layer "F.Fab")
		)
		(fp_line
			(start -0.12065 0.2794)
			(end -0.12065 0.3048)
			(stroke
				(width 0.1)
				(type default)
			)
			(layer "F.Fab")
		)
		(fp_line
			(start 0.120396 0.2794)
			(end -0.12065 0.2794)
			(stroke
				(width 0.1)
				(type default)
			)
			(layer "F.Fab")
		)
		(fp_line
			(start -0.12065 -0.2794)
			(end 0.12065 -0.2794)
			(stroke
				(width 0.1)
				(type default)
			)
			(layer "F.Fab")
		)
		(fp_line
			(start 0.12065 -0.2794)
			(end 0.12065 -0.3048)
			(stroke
				(width 0.1)
				(type default)
			)
			(layer "F.Fab")
		)
		(fp_line
			(start 0.12065 -0.3048)
			(end 0.67945 -0.3048)
			(stroke
				(width 0.1)
				(type default)
			)
			(layer "F.Fab")
		)
		(fp_line
			(start 0.67945 -0.3048)
			(end 0.67945 0.3048)
			(stroke
				(width 0.1)
				(type default)
			)
			(layer "F.Fab")
		)
		(fp_line
			(start -0.67945 -0.305054)
			(end -0.12065 -0.305054)
			(stroke
				(width 0.1)
				(type default)
			)
			(layer "F.Fab")
		)
		(fp_line
			(start -0.12065 -0.305054)
			(end -0.12065 -0.2794)
			(stroke
				(width 0.1)
				(type default)
			)
			(layer "F.Fab")
		)
		(pad "1" smd circle
			(at -0.40005 0 270)
			(size 0 0)
			(layers "F.Cu" "F.Mask" "F.Paste")
			(net "USB3_01_MUX_FB_TXN")
		)
		(pad "2" smd circle
			(at 0.40005 0 270)
			(size 0 0)
			(layers "F.Cu" "F.Mask" "F.Paste")
			(net "USB3_01_FB_TXN")
		)
	)
	(footprint ""
		(layer "F.Cu")
		(at 39.50462 -30.63748 90)
		(property "Reference" "R213"
			(at 0 0 90)
			(layer "F.SilkS")
			(hide yes)
			(effects
				(font
					(size 1.27 1.27)
				)
			)
		)
		(property "Value" ""
			(at 0 0 90)
			(layer "F.Fab")
			(effects
				(font
					(size 1.27 1.27)
				)
			)
		)
		(duplicate_pad_numbers_are_jumpers no)
		(fp_line
			(start 0.7874 -0.4064)
			(end 0.7874 0.4064)
			(stroke
				(width 0.1524)
				(type default)
			)
			(layer "F.SilkS")
		)
		(fp_line
			(start -0.7874 -0.4064)
			(end 0.7874 -0.4064)
			(stroke
				(width 0.1524)
				(type default)
			)
			(layer "F.SilkS")
		)
		(fp_line
			(start 0.7874 0.4064)
			(end -0.7874 0.4064)
			(stroke
				(width 0.1524)
				(type default)
			)
			(layer "F.SilkS")
		)
		(fp_line
			(start -0.7874 0.4064)
			(end -0.7874 -0.4064)
			(stroke
				(width 0.1524)
				(type default)
			)
			(layer "F.SilkS")
		)
		(fp_line
			(start -0.12065 -0.305054)
			(end -0.12065 -0.2794)
			(stroke
				(width 0.1)
				(type default)
			)
			(layer "F.Fab")
		)
		(fp_line
			(start -0.67945 -0.305054)
			(end -0.12065 -0.305054)
			(stroke
				(width 0.1)
				(type default)
			)
			(layer "F.Fab")
		)
		(fp_line
			(start 0.67945 -0.3048)
			(end 0.67945 0.3048)
			(stroke
				(width 0.1)
				(type default)
			)
			(layer "F.Fab")
		)
		(fp_line
			(start 0.12065 -0.3048)
			(end 0.67945 -0.3048)
			(stroke
				(width 0.1)
				(type default)
			)
			(layer "F.Fab")
		)
		(fp_line
			(start 0.12065 -0.2794)
			(end 0.12065 -0.3048)
			(stroke
				(width 0.1)
				(type default)
			)
			(layer "F.Fab")
		)
		(fp_line
			(start -0.12065 -0.2794)
			(end 0.12065 -0.2794)
			(stroke
				(width 0.1)
				(type default)
			)
			(layer "F.Fab")
		)
		(fp_line
			(start 0.120396 0.2794)
			(end -0.12065 0.2794)
			(stroke
				(width 0.1)
				(type default)
			)
			(layer "F.Fab")
		)
		(fp_line
			(start -0.12065 0.2794)
			(end -0.12065 0.3048)
			(stroke
				(width 0.1)
				(type default)
			)
			(layer "F.Fab")
		)
		(fp_line
			(start 0.67945 0.3048)
			(end 0.120396 0.3048)
			(stroke
				(width 0.1)
				(type default)
			)
			(layer "F.Fab")
		)
		(fp_line
			(start 0.120396 0.3048)
			(end 0.120396 0.2794)
			(stroke
				(width 0.1)
				(type default)
			)
			(layer "F.Fab")
		)
		(fp_line
			(start -0.12065 0.3048)
			(end -0.67945 0.3048)
			(stroke
				(width 0.1)
				(type default)
			)
			(layer "F.Fab")
		)
		(fp_line
			(start -0.67945 0.3048)
			(end -0.67945 -0.305054)
			(stroke
				(width 0.1)
				(type default)
			)
			(layer "F.Fab")
		)
		(pad "1" smd circle
			(at -0.40005 0 90)
			(size 0 0)
			(layers "F.Cu" "F.Mask" "F.Paste")
			(net "P3V3_AUX")
		)
		(pad "2" smd circle
			(at 0.40005 0 90)
			(size 0 0)
			(layers "F.Cu" "F.Mask" "F.Paste")
			(net "P3V3_P1V8_SD2VDD")
		)
	)
)
